# TIMECARD (Time Appliance Project (Time Card)) — schematic netlist excerpt (pin names and nets, part order shuffled) for the footprints in the layout excerpt that follows; sources: Cadence DE-HDL packaged netlist, KiCad conversion of R4006-B0001-02_R01.brd

R213  RESISTOR  10KOHM 1%  pkg SMC_0402R_H016  page 10 : \1\ = XP3R3V_FPGA ; \2\ = FPGA_BRD_REV2
L16  FERRITEBEAD  120OHM 25%  pkg SMC_0603R_H030  page 22 : \1\ = XP3R3V_GPS ; \2\ = XP3R3V_FPGA

(kicad_pcb
	(version 20260206)
	(generator "pcbnew")
	(generator_version "10.0")
	(general
		(thickness 1.6)
		(legacy_teardrops no)
	)
	(paper "A4")
	(title_block
		(title "timecard-production-celestica-r4006 — R4006-B0001-02_R01.brd")
		(comment 1 "Time Appliance Project (Time Card) / footprints 576-577 of 1113")
	)
	(layers
		(0 "F.Cu" signal "TOP")
		(4 "In1.Cu" signal "L02_GND1")
		(6 "In2.Cu" signal "L03_SIG1")
		(8 "In3.Cu" signal "L04_GND2")
		(10 "In4.Cu" signal "L05_VCC1")
		(12 "In5.Cu" signal "L06_VCC2")
		(14 "In6.Cu" signal "L07_GND3")
		(16 "In7.Cu" signal "L08_SIG2")
		(18 "In8.Cu" signal "L09_GND4")
		(2 "B.Cu" signal "BOTTOM")
		(9 "F.Adhes" user "F.Adhesive")
		(11 "B.Adhes" user "B.Adhesive")
		(13 "F.Paste" user "Package Geometry/Pastemask Top")
		(15 "B.Paste" user "Package Geometry/Pastemask Bottom")
		(5 "F.SilkS" user "Ref Des/Silkscreen Top")
		(7 "B.SilkS" user "Ref Des/Silkscreen Bottom")
		(1 "F.Mask" user "Board Geometry/Soldermask Top")
		(3 "B.Mask" user "Board Geometry/Soldermask Bottom")
		(17 "Dwgs.User" user "User.Drawings")
		(19 "Cmts.User" user "User.Comments")
		(21 "Eco1.User" user "User.Eco1")
		(23 "Eco2.User" user "User.Eco2")
		(25 "Edge.Cuts" user "Board Geometry/Outline")
		(27 "Margin" user)
		(31 "F.CrtYd" user "Package Geometry/Place Bound Top")
		(29 "B.CrtYd" user "Package Geometry/Place Bound Bottom")
		(35 "F.Fab" user "Ref Des/Assembly Top")
		(33 "B.Fab" user "Ref Des/Assembly Bottom")
	)
	(footprint ""
		(layer "F.Cu")
		(at 117.475 -98.044 180)
		(property "Reference" "L16"
			(at 1.0795 -1.43637 0)
			(unlocked yes)
			(layer "F.SilkS")
			(effects
				(font
					(size 0.7874 0.5842)
					(thickness 0.1524)
				)
				(justify left)
			)
		)
		(property "Value" "VAL*"
			(at -0.9398 3.70967 180)
			(unlocked yes)
			(layer "F.Fab")
			(hide yes)
			(effects
				(font
					(size 0.7874 0.5842)
					(thickness 0.1524)
				)
				(justify left)
			)
		)
		(property "Tolerance" "TOL*"
			(at -0.9906 5.00507 180)
			(unlocked yes)
			(layer "Cmts.User")
			(hide yes)
			(effects
				(font
					(size 0.7874 0.5842)
					(thickness 0.1524)
				)
				(justify left)
			)
		)
		(property "User Part Number" "PARTNUM*"
			(at -2.54 2.46507 180)
			(unlocked yes)
			(layer "Cmts.User")
			(hide yes)
			(effects
				(font
					(size 0.7874 0.5842)
					(thickness 0.1524)
				)
				(justify left)
			)
		)
		(property "Device Type" "FERRITEBEAD-G191-10100-01,120OA"
			(at -0.9906 1.22047 180)
			(unlocked yes)
			(layer "F.Fab")
			(hide yes)
			(effects
				(font
					(size 0.7874 0.5842)
					(thickness 0.1524)
				)
				(justify left)
			)
		)
		(duplicate_pad_numbers_are_jumpers no)
		(fp_line
			(start 1.3208 0.7112)
			(end -1.3208 0.7112)
			(stroke
				(width 0.1)
				(type default)
			)
			(layer "F.SilkS")
		)
		(fp_line
			(start 1.3208 -0.7112)
			(end 1.3208 0.7112)
			(stroke
				(width 0.1)
				(type default)
			)
			(layer "F.SilkS")
		)
		(fp_line
			(start -1.3208 0.7112)
			(end -1.3208 -0.7112)
			(stroke
				(width 0.1)
				(type default)
			)
			(layer "F.SilkS")
		)
		(fp_line
			(start -1.3208 -0.7112)
			(end 1.3208 -0.7112)
			(stroke
				(width 0.1)
				(type default)
			)
			(layer "F.SilkS")
		)
		(fp_rect
			(start -1.3208 0.7112)
			(end 1.3208 -0.7112)
			(stroke
				(width 0)
				(type default)
			)
			(fill no)
			(layer "F.CrtYd")
		)
		(fp_line
			(start 0.8128 0.4572)
			(end -0.8128 0.4572)
			(stroke
				(width 0.1)
				(type default)
			)
			(layer "F.Fab")
		)
		(fp_line
			(start 0.8128 -0.4572)
			(end 0.8128 0.4572)
			(stroke
				(width 0.1)
				(type default)
			)
			(layer "F.Fab")
		)
		(fp_line
			(start -0.8128 0.4572)
			(end -0.8128 -0.4572)
			(stroke
				(width 0.1)
				(type default)
			)
			(layer "F.Fab")
		)
		(fp_line
			(start -0.8128 -0.4572)
			(end 0.8128 -0.4572)
			(stroke
				(width 0.1)
				(type default)
			)
			(layer "F.Fab")
		)
		(pad "1" smd rect
			(at -0.6858 0 180)
			(size 0.762 0.8636)
			(layers "F.Cu" "F.Mask" "F.Paste")
			(net "XP3R3V_GPS")
		)
		(pad "2" smd rect
			(at 0.6858 0 180)
			(size 0.762 0.8636)
			(layers "F.Cu" "F.Mask" "F.Paste")
			(net "XP3R3V_FPGA")
		)
		(zone
			(layer "F.Cu")
			(hatch none 0.5)
			(connect_pads
				(clearance 0)
			)
			(min_thickness 0.25)
			(keepout
				(tracks allowed)
				(vias not_allowed)
				(pads allowed)
				(copperpour not_allowed)
				(footprints allowed)
			)
			(placement
				(enabled no)
				(sheetname "")
			)
			(fill
				(thermal_gap 0.5)
				(thermal_bridge_width 0.5)
				(island_removal_mode 0)
			)
			(polygon
				(pts
					(xy 117.6274 -98.5012) (xy 117.3226 -98.5012) (xy 117.3226 -97.5868) (xy 117.6274 -97.5868)
				)
			)
		)
		(zone
			(layer "F.Cu")
			(hatch none 0.5)
			(connect_pads
				(clearance 0)
			)
			(min_thickness 0.25)
			(keepout
				(tracks not_allowed)
				(vias allowed)
				(pads allowed)
				(copperpour not_allowed)
				(footprints allowed)
			)
			(placement
				(enabled no)
				(sheetname "")
			)
			(fill
				(thermal_gap 0.5)
				(thermal_bridge_width 0.5)
				(island_removal_mode 0)
			)
			(polygon
				(pts
					(xy 117.6274 -98.5012) (xy 117.3226 -98.5012) (xy 117.3226 -97.5868) (xy 117.6274 -97.5868)
				)
			)
		)
	)
	(footprint ""
		(layer "F.Cu")
		(at 111.633 -61.976 -90)
		(property "Reference" "R213"
			(at -3.302 -0.42037 90)
			(unlocked yes)
			(layer "F.SilkS")
			(effects
				(font
					(size 0.7874 0.5842)
					(thickness 0.1524)
				)
			)
		)
		(property "Value" "VAL*"
			(at 0.02032 2.13233 270)
			(unlocked yes)
			(layer "F.Fab")
			(hide yes)
			(effects
				(font
					(size 0.7874 0.5842)
					(thickness 0.1524)
				)
			)
		)
		(property "Device Type" "RESISTOR-G155-11002-01,10KOHM,A"
			(at 0.008382 1.210564 270)
			(unlocked yes)
			(layer "F.Fab")
			(hide yes)
			(effects
				(font
					(size 0.7874 0.5842)
					(thickness 0.1524)
				)
			)
		)
		(property "User Part Number" "PARTNUM*"
			(at 0.02032 4.024884 270)
			(unlocked yes)
			(layer "Cmts.User")
			(hide yes)
			(effects
				(font
					(size 0.7874 0.5842)
					(thickness 0.1524)
				)
			)
		)
		(property "Tolerance" "TOL*"
			(at 0.044704 3.05435 270)
			(unlocked yes)
			(layer "Cmts.User")
			(hide yes)
			(effects
				(font
					(size 0.7874 0.5842)
					(thickness 0.1524)
				)
			)
		)
		(duplicate_pad_numbers_are_jumpers no)
		(fp_line
			(start -1.143 0.5588)
			(end 1.143 0.5588)
			(stroke
				(width 0.1)
				(type default)
			)
			(layer "F.SilkS")
		)
		(fp_line
			(start 1.143 0.5588)
			(end 1.143 -0.5588)
			(stroke
				(width 0.1)
				(type default)
			)
			(layer "F.SilkS")
		)
		(fp_line
			(start -1.143 -0.5588)
			(end -1.143 0.5588)
			(stroke
				(width 0.1)
				(type default)
			)
			(layer "F.SilkS")
		)
		(fp_line
			(start 1.143 -0.5588)
			(end -1.143 -0.5588)
			(stroke
				(width 0.1)
				(type default)
			)
			(layer "F.SilkS")
		)
		(fp_rect
			(start 1.143 0.5588)
			(end -1.143 -0.5588)
			(stroke
				(width 0)
				(type default)
			)
			(fill no)
			(layer "F.CrtYd")
		)
		(fp_line
			(start -0.508 0.3048)
			(end 0.508 0.3048)
			(stroke
				(width 0.1)
				(type default)
			)
			(layer "F.Fab")
		)
		(fp_line
			(start 0.508 0.3048)
			(end 0.508 -0.3048)
			(stroke
				(width 0.1)
				(type default)
			)
			(layer "F.Fab")
		)
		(fp_line
			(start -0.508 -0.3048)
			(end -0.508 0.3048)
			(stroke
				(width 0.1)
				(type default)
			)
			(layer "F.Fab")
		)
		(fp_line
			(start 0.508 -0.3048)
			(end -0.508 -0.3048)
			(stroke
				(width 0.1)
				(type default)
			)
			(layer "F.Fab")
		)
		(pad "1" smd rect
			(at -0.5334 0 270)
			(size 0.7112 0.6096)
			(layers "F.Cu" "F.Mask" "F.Paste")
			(net "XP3R3V_FPGA")
		)
		(pad "2" smd rect
			(at 0.5334 0 270)
			(size 0.7112 0.6096)
			(layers "F.Cu" "F.Mask" "F.Paste")
			(net "FPGA_BRD_REV2")
		)
		(zone
			(layer "F.Cu")
			(hatch none 0.5)
			(connect_pads
				(clearance 0)
			)
			(min_thickness 0.25)
			(keepout
				(tracks allowed)
				(vias not_allowed)
				(pads allowed)
				(copperpour not_allowed)
				(footprints allowed)
			)
			(placement
				(enabled no)
				(sheetname "")
			)
			(fill
				(thermal_gap 0.5)
				(thermal_bridge_width 0.5)
				(island_removal_mode 0)
			)
			(polygon
				(pts
					(xy 111.3282 -61.8998) (xy 111.9378 -61.8998) (xy 111.9378 -62.0522) (xy 111.3282 -62.0522)
				)
			)
		)
	)
)
